(kicad_pcb
	(version 20260206)
	(generator "pcbnew")
	(generator_version "10.0")
	(general
		(thickness 1.6)
		(legacy_teardrops no)
	)
	(paper "A4")
	(title_block
		(title "03242023_DA0F0TMBIJ0_F0T_Motherboard_J_brd_V01_OCP.brd")
		(comment 1 "Grand Teton / footprints 2333-2337 of 6105")
	)
	(layers
		(0 "F.Cu" signal "TOP")
		(4 "In1.Cu" signal "GND")
		(6 "In2.Cu" signal "IN1")
		(8 "In3.Cu" signal "GND1")
		(10 "In4.Cu" signal "IN2")
		(12 "In5.Cu" signal "GND2")
		(14 "In6.Cu" signal "IN3")
		(16 "In7.Cu" signal "GND3")
		(18 "In8.Cu" signal "VCC")
		(20 "In9.Cu" signal "VCC1")
		(22 "In10.Cu" signal "GND4")
		(24 "In11.Cu" signal "IN4")
		(26 "In12.Cu" signal "GND5")
		(28 "In13.Cu" signal "IN5")
		(30 "In14.Cu" signal "GND6")
		(32 "In15.Cu" signal "IN6")
		(34 "In16.Cu" signal "GND7")
		(2 "B.Cu" signal "BOTTOM")
		(9 "F.Adhes" user "F.Adhesive")
		(11 "B.Adhes" user "B.Adhesive")
		(13 "F.Paste" user "Package Geometry/Pastemask Top")
		(15 "B.Paste" user "Package Geometry/Pastemask Bottom")
		(5 "F.SilkS" user "Ref Des/Silkscreen Top")
		(7 "B.SilkS" user "Ref Des/Silkscreen Bottom")
		(1 "F.Mask" user "Board Geometry/Soldermask Top")
		(3 "B.Mask" user "Board Geometry/Soldermask Bottom")
		(17 "Dwgs.User" user "User.Drawings")
		(19 "Cmts.User" user "User.Comments")
		(21 "Eco1.User" user "User.Eco1")
		(23 "Eco2.User" user "User.Eco2")
		(25 "Edge.Cuts" user "Board Geometry/Outline")
		(27 "Margin" user)
		(31 "F.CrtYd" user "Package Geometry/Place Bound Top")
		(29 "B.CrtYd" user "Package Geometry/Place Bound Bottom")
		(35 "F.Fab" user "Ref Des/Assembly Top")
		(33 "B.Fab" user "Ref Des/Assembly Bottom")
	)
	(footprint ""
		(layer "F.Cu")
		(at 465.036408 -382.750314 90)
		(property "Reference" "PL64"
			(at 0 0 90)
			(layer "F.SilkS")
			(hide yes)
			(effects
				(font
					(size 1.27 1.27)
				)
			)
		)
		(property "Value" ""
			(at 0 0 90)
			(layer "F.Fab")
			(effects
				(font
					(size 1.27 1.27)
				)
			)
		)
		(duplicate_pad_numbers_are_jumpers no)
		(fp_line
			(start -1.27 -0.5842)
			(end 1.27 -0.5842)
			(stroke
				(width 0.1524)
				(type default)
			)
			(layer "F.SilkS")
		)
		(fp_line
			(start -1.27 -0.5588)
			(end -1.27 -0.5842)
			(stroke
				(width 0.1524)
				(type default)
			)
			(layer "F.SilkS")
		)
		(fp_line
			(start 1.27 0.5842)
			(end 1.27 -0.5842)
			(stroke
				(width 0.1524)
				(type default)
			)
			(layer "F.SilkS")
		)
		(fp_line
			(start 1.27 0.5842)
			(end -1.27 0.5842)
			(stroke
				(width 0.1524)
				(type default)
			)
			(layer "F.SilkS")
		)
		(fp_line
			(start 0.127 0.5842)
			(end 0.127 -0.5842)
			(stroke
				(width 0.1524)
				(type default)
			)
			(layer "F.SilkS")
		)
		(fp_line
			(start -0.127 0.5842)
			(end -0.127 -0.5842)
			(stroke
				(width 0.1524)
				(type default)
			)
			(layer "F.SilkS")
		)
		(fp_line
			(start -1.27 0.5842)
			(end -1.27 -0.5842)
			(stroke
				(width 0.1524)
				(type default)
			)
			(layer "F.SilkS")
		)
		(fp_line
			(start 0.9144 -0.508)
			(end 0.9144 -0.406654)
			(stroke
				(width 0.1)
				(type default)
			)
			(layer "F.Fab")
		)
		(fp_line
			(start -0.9144 -0.508)
			(end 0.9144 -0.508)
			(stroke
				(width 0.1)
				(type default)
			)
			(layer "F.Fab")
		)
		(fp_line
			(start 1.1938 -0.406654)
			(end 1.1938 0.4064)
			(stroke
				(width 0.1)
				(type default)
			)
			(layer "F.Fab")
		)
		(fp_line
			(start 0.9144 -0.406654)
			(end 1.1938 -0.406654)
			(stroke
				(width 0.1)
				(type default)
			)
			(layer "F.Fab")
		)
		(fp_line
			(start -0.9144 -0.406654)
			(end -0.9144 -0.508)
			(stroke
				(width 0.1)
				(type default)
			)
			(layer "F.Fab")
		)
		(fp_line
			(start -1.194308 -0.406654)
			(end -0.9144 -0.406654)
			(stroke
				(width 0.1)
				(type default)
			)
			(layer "F.Fab")
		)
		(fp_line
			(start 1.1938 0.4064)
			(end 0.9144 0.4064)
			(stroke
				(width 0.1)
				(type default)
			)
			(layer "F.Fab")
		)
		(fp_line
			(start 0.9144 0.4064)
			(end 0.9144 0.508)
			(stroke
				(width 0.1)
				(type default)
			)
			(layer "F.Fab")
		)
		(fp_line
			(start -0.9144 0.406654)
			(end -1.194308 0.406654)
			(stroke
				(width 0.1)
				(type default)
			)
			(layer "F.Fab")
		)
		(fp_line
			(start -1.194308 0.406654)
			(end -1.194308 -0.406654)
			(stroke
				(width 0.1)
				(type default)
			)
			(layer "F.Fab")
		)
		(fp_line
			(start 0.9144 0.508)
			(end -0.9144 0.508)
			(stroke
				(width 0.1)
				(type default)
			)
			(layer "F.Fab")
		)
		(fp_line
			(start -0.9144 0.508)
			(end -0.9144 0.406654)
			(stroke
				(width 0.1)
				(type default)
			)
			(layer "F.Fab")
		)
		(pad "1" smd rect
			(at -0.7366 0)
			(size 0.7112 0.8128)
			(layers "F.Cu" "F.Mask" "F.Paste")
			(net "P12V_AUX")
		)
		(pad "2" smd rect
			(at 0.7366 0)
			(size 0.7112 0.8128)
			(layers "F.Cu" "F.Mask" "F.Paste")
			(net "SW_P5V_AUX_FLT")
		)
	)
	(footprint ""
		(layer "F.Cu")
		(at 260.731508 5.463794)
		(property "Reference" "J78"
			(at -4.164838 1.013206 90)
			(unlocked yes)
			(layer "F.SilkS")
			(effects
				(font
					(size 0.7874 0.5842)
					(thickness 0.1524)
				)
				(justify left)
			)
		)
		(property "Value" ""
			(at 0 0 0)
			(layer "F.Fab")
			(effects
				(font
					(size 1.27 1.27)
				)
			)
		)
		(duplicate_pad_numbers_are_jumpers no)
		(fp_line
			(start -1.2192 -2.1082)
			(end 1.2192 -2.1082)
			(stroke
				(width 0.1524)
				(type default)
			)
			(layer "F.SilkS")
		)
		(fp_line
			(start -1.2192 2.1082)
			(end -1.2192 -2.1082)
			(stroke
				(width 0.1524)
				(type default)
			)
			(layer "F.SilkS")
		)
		(fp_line
			(start 1.2192 -2.1082)
			(end 1.2192 2.1082)
			(stroke
				(width 0.1524)
				(type default)
			)
			(layer "F.SilkS")
		)
		(fp_line
			(start 1.2192 2.1082)
			(end -1.2192 2.1082)
			(stroke
				(width 0.1524)
				(type default)
			)
			(layer "F.SilkS")
		)
		(pad "" np_thru_hole circle
			(at -2.8829 -1.27 270)
			(size 1.0414 1.0414)
			(drill 1.0414)
			(layers "*.Cu" "*.Mask")
			(clearance 0.381)
			(thermal_gap 0.381)
		)
		(pad "" np_thru_hole circle
			(at -2.8829 1.27 270)
			(size 1.0414 1.0414)
			(drill 1.0414)
			(layers "*.Cu" "*.Mask")
			(clearance 0.381)
			(thermal_gap 0.381)
		)
		(pad "" np_thru_hole circle
			(at 3.4671 -1.27 270)
			(size 1.0414 1.0414)
			(drill 1.0414)
			(layers "*.Cu" "*.Mask")
			(clearance 0.381)
			(thermal_gap 0.381)
		)
		(pad "" np_thru_hole circle
			(at 3.4671 1.27 270)
			(size 1.0414 1.0414)
			(drill 1.0414)
			(layers "*.Cu" "*.Mask")
			(clearance 0.381)
			(thermal_gap 0.381)
		)
		(pad "1" smd rect
			(at 0.8255 -0.249936 270)
			(size 0.3048 0.508)
			(layers "F.Cu" "F.Mask" "F.Paste")
			(net "DELTA_L_85_10INCH_IN2_DP")
		)
		(pad "2" smd rect
			(at 0.8255 0.249936 270)
			(size 0.3048 0.508)
			(layers "F.Cu" "F.Mask" "F.Paste")
			(net "DELTA_L_85_10INCH_IN2_DN")
		)
		(pad "3" smd circle
			(at 0 0)
			(size 0 0)
			(layers "F.Cu" "F.Mask" "F.Paste")
			(net "DELTA_L_GND_1")
		)
		(zone
			(layer "F.Cu")
			(hatch none 0.5)
			(connect_pads
				(clearance 0)
			)
			(min_thickness 0.25)
			(keepout
				(tracks not_allowed)
				(vias allowed)
				(pads allowed)
				(copperpour not_allowed)
				(footprints allowed)
			)
			(placement
				(enabled no)
				(sheetname "")
			)
			(fill
				(thermal_gap 0.5)
				(thermal_bridge_width 0.5)
				(island_removal_mode 0)
			)
			(polygon
				(pts
					(xy 261.849108 4.915154) (xy 261.849108 5.010658) (xy 261.252208 5.010658) (xy 261.252208 5.417058)
					(xy 261.849108 5.417058) (xy 261.849108 5.51053) (xy 261.252208 5.51053) (xy 261.252208 5.91693)
					(xy 261.849108 5.91693) (xy 261.849108 6.012434) (xy 261.150608 6.012434) (xy 261.150608 4.915154)
				)
			)
		)
		(zone
			(layers "F.Cu" "B.Cu" "In1.Cu" "In2.Cu" "In3.Cu" "In4.Cu" "In5.Cu" "In6.Cu"
				"In7.Cu" "In8.Cu" "In9.Cu" "In10.Cu" "In11.Cu" "In12.Cu" "In13.Cu" "In14.Cu"
				"In15.Cu" "In16.Cu"
			)
			(hatch none 0.5)
			(connect_pads
				(clearance 0)
			)
			(min_thickness 0.25)
			(keepout
				(tracks not_allowed)
				(vias allowed)
				(pads allowed)
				(copperpour not_allowed)
				(footprints allowed)
			)
			(placement
				(enabled no)
				(sheetname "")
			)
			(fill
				(thermal_gap 0.5)
				(thermal_bridge_width 0.5)
				(island_removal_mode 0)
			)
			(polygon
				(pts
					(arc
						(start 258.775708 4.193794)
						(mid 256.921508 4.193794)
						(end 258.775708 4.193794)
					)
				)
			)
		)
		(zone
			(layers "F.Cu" "B.Cu" "In1.Cu" "In2.Cu" "In3.Cu" "In4.Cu" "In5.Cu" "In6.Cu"
				"In7.Cu" "In8.Cu" "In9.Cu" "In10.Cu" "In11.Cu" "In12.Cu" "In13.Cu" "In14.Cu"
				"In15.Cu" "In16.Cu"
			)
			(hatch none 0.5)
			(connect_pads
				(clearance 0)
			)
			(min_thickness 0.25)
			(keepout
				(tracks not_allowed)
				(vias allowed)
				(pads allowed)
				(copperpour not_allowed)
				(footprints allowed)
			)
			(placement
				(enabled no)
				(sheetname "")
			)
			(fill
				(thermal_gap 0.5)
				(thermal_bridge_width 0.5)
				(island_removal_mode 0)
			)
			(polygon
				(pts
					(arc
						(start 258.775708 6.733794)
						(mid 256.921508 6.733794)
						(end 258.775708 6.733794)
					)
				)
			)
		)
		(zone
			(layers "F.Cu" "B.Cu" "In1.Cu" "In2.Cu" "In3.Cu" "In4.Cu" "In5.Cu" "In6.Cu"
				"In7.Cu" "In8.Cu" "In9.Cu" "In10.Cu" "In11.Cu" "In12.Cu" "In13.Cu" "In14.Cu"
				"In15.Cu" "In16.Cu"
			)
			(hatch none 0.5)
			(connect_pads
				(clearance 0)
			)
			(min_thickness 0.25)
			(keepout
				(tracks not_allowed)
				(vias allowed)
				(pads allowed)
				(copperpour not_allowed)
				(footprints allowed)
			)
			(placement
				(enabled no)
				(sheetname "")
			)
			(fill
				(thermal_gap 0.5)
				(thermal_bridge_width 0.5)
				(island_removal_mode 0)
			)
			(polygon
				(pts
					(arc
						(start 265.125708 4.193794)
						(mid 263.271508 4.193794)
						(end 265.125708 4.193794)
					)
				)
			)
		)
		(zone
			(layers "F.Cu" "B.Cu" "In1.Cu" "In2.Cu" "In3.Cu" "In4.Cu" "In5.Cu" "In6.Cu"
				"In7.Cu" "In8.Cu" "In9.Cu" "In10.Cu" "In11.Cu" "In12.Cu" "In13.Cu" "In14.Cu"
				"In15.Cu" "In16.Cu"
			)
			(hatch none 0.5)
			(connect_pads
				(clearance 0)
			)
			(min_thickness 0.25)
			(keepout
				(tracks not_allowed)
				(vias allowed)
				(pads allowed)
				(copperpour not_allowed)
				(footprints allowed)
			)
			(placement
				(enabled no)
				(sheetname "")
			)
			(fill
				(thermal_gap 0.5)
				(thermal_bridge_width 0.5)
				(island_removal_mode 0)
			)
			(polygon
				(pts
					(arc
						(start 265.125708 6.733794)
						(mid 263.271508 6.733794)
						(end 265.125708 6.733794)
					)
				)
			)
		)
	)
	(footprint ""
		(layer "F.Cu")
		(at 294.045894 -415.00552)
		(property "Reference" "R4687"
			(at 0 0 0)
			(layer "F.SilkS")
			(hide yes)
			(effects
				(font
					(size 1.27 1.27)
				)
			)
		)
		(property "Value" ""
			(at 0 0 0)
			(layer "F.Fab")
			(effects
				(font
					(size 1.27 1.27)
				)
			)
		)
		(duplicate_pad_numbers_are_jumpers no)
		(fp_line
			(start -0.7874 -0.4064)
			(end 0.7874 -0.4064)
			(stroke
				(width 0.1524)
				(type default)
			)
			(layer "F.SilkS")
		)
		(fp_line
			(start -0.7874 0.4064)
			(end -0.7874 -0.4064)
			(stroke
				(width 0.1524)
				(type default)
			)
			(layer "F.SilkS")
		)
		(fp_line
			(start 0.7874 -0.4064)
			(end 0.7874 0.4064)
			(stroke
				(width 0.1524)
				(type default)
			)
			(layer "F.SilkS")
		)
		(fp_line
			(start 0.7874 0.4064)
			(end -0.7874 0.4064)
			(stroke
				(width 0.1524)
				(type default)
			)
			(layer "F.SilkS")
		)
		(fp_line
			(start -0.67945 -0.305054)
			(end -0.12065 -0.305054)
			(stroke
				(width 0.1)
				(type default)
			)
			(layer "F.Fab")
		)
		(fp_line
			(start -0.67945 0.3048)
			(end -0.67945 -0.305054)
			(stroke
				(width 0.1)
				(type default)
			)
			(layer "F.Fab")
		)
		(fp_line
			(start -0.12065 -0.305054)
			(end -0.12065 -0.2794)
			(stroke
				(width 0.1)
				(type default)
			)
			(layer "F.Fab")
		)
		(fp_line
			(start -0.12065 -0.2794)
			(end 0.12065 -0.2794)
			(stroke
				(width 0.1)
				(type default)
			)
			(layer "F.Fab")
		)
		(fp_line
			(start -0.12065 0.2794)
			(end -0.12065 0.3048)
			(stroke
				(width 0.1)
				(type default)
			)
			(layer "F.Fab")
		)
		(fp_line
			(start -0.12065 0.3048)
			(end -0.67945 0.3048)
			(stroke
				(width 0.1)
				(type default)
			)
			(layer "F.Fab")
		)
		(fp_line
			(start 0.120396 0.2794)
			(end -0.12065 0.2794)
			(stroke
				(width 0.1)
				(type default)
			)
			(layer "F.Fab")
		)
		(fp_line
			(start 0.120396 0.3048)
			(end 0.120396 0.2794)
			(stroke
				(width 0.1)
				(type default)
			)
			(layer "F.Fab")
		)
		(fp_line
			(start 0.12065 -0.3048)
			(end 0.67945 -0.3048)
			(stroke
				(width 0.1)
				(type default)
			)
			(layer "F.Fab")
		)
		(fp_line
			(start 0.12065 -0.2794)
			(end 0.12065 -0.3048)
			(stroke
				(width 0.1)
				(type default)
			)
			(layer "F.Fab")
		)
		(fp_line
			(start 0.67945 -0.3048)
			(end 0.67945 0.3048)
			(stroke
				(width 0.1)
				(type default)
			)
			(layer "F.Fab")
		)
		(fp_line
			(start 0.67945 0.3048)
			(end 0.120396 0.3048)
			(stroke
				(width 0.1)
				(type default)
			)
			(layer "F.Fab")
		)
		(pad "1" smd circle
			(at -0.40005 0)
			(size 0 0)
			(layers "F.Cu" "F.Mask" "F.Paste")
			(net "GND")
		)
		(pad "2" smd circle
			(at 0.40005 0)
			(size 0 0)
			(layers "F.Cu" "F.Mask" "F.Paste")
			(net "HSC_TYPE_ADC_A1")
		)
	)
	(footprint ""
		(layer "F.Cu")
		(at 178.960272 -358.135936 -90)
		(property "Reference" "PC1369"
			(at 0 0 270)
			(layer "F.SilkS")
			(hide yes)
			(effects
				(font
					(size 1.27 1.27)
				)
			)
		)
		(property "Value" ""
			(at 0 0 270)
			(layer "F.Fab")
			(effects
				(font
					(size 1.27 1.27)
				)
			)
		)
		(duplicate_pad_numbers_are_jumpers no)
		(fp_line
			(start -0.7874 0.4064)
			(end -0.7874 -0.4064)
			(stroke
				(width 0.1524)
				(type default)
			)
			(layer "F.SilkS")
		)
		(fp_line
			(start 0.7874 0.4064)
			(end -0.7874 0.4064)
			(stroke
				(width 0.1524)
				(type default)
			)
			(layer "F.SilkS")
		)
		(fp_line
			(start -0.7874 -0.4064)
			(end 0.7874 -0.4064)
			(stroke
				(width 0.1524)
				(type default)
			)
			(layer "F.SilkS")
		)
		(fp_line
			(start 0.7874 -0.4064)
			(end 0.7874 0.4064)
			(stroke
				(width 0.1524)
				(type default)
			)
			(layer "F.SilkS")
		)
		(fp_line
			(start -0.67945 0.3048)
			(end -0.67945 -0.305054)
			(stroke
				(width 0.1)
				(type default)
			)
			(layer "F.Fab")
		)
		(fp_line
			(start -0.12065 0.3048)
			(end -0.67945 0.3048)
			(stroke
				(width 0.1)
				(type default)
			)
			(layer "F.Fab")
		)
		(fp_line
			(start 0.120396 0.3048)
			(end 0.120396 0.2794)
			(stroke
				(width 0.1)
				(type default)
			)
			(layer "F.Fab")
		)
		(fp_line
			(start 0.67945 0.3048)
			(end 0.120396 0.3048)
			(stroke
				(width 0.1)
				(type default)
			)
			(layer "F.Fab")
		)
		(fp_line
			(start -0.12065 0.2794)
			(end -0.12065 0.3048)
			(stroke
				(width 0.1)
				(type default)
			)
			(layer "F.Fab")
		)
		(fp_line
			(start 0.120396 0.2794)
			(end -0.12065 0.2794)
			(stroke
				(width 0.1)
				(type default)
			)
			(layer "F.Fab")
		)
		(fp_line
			(start -0.12065 -0.2794)
			(end 0.12065 -0.2794)
			(stroke
				(width 0.1)
				(type default)
			)
			(layer "F.Fab")
		)
		(fp_line
			(start 0.12065 -0.2794)
			(end 0.12065 -0.3048)
			(stroke
				(width 0.1)
				(type default)
			)
			(layer "F.Fab")
		)
		(fp_line
			(start 0.12065 -0.3048)
			(end 0.67945 -0.3048)
			(stroke
				(width 0.1)
				(type default)
			)
			(layer "F.Fab")
		)
		(fp_line
			(start 0.67945 -0.3048)
			(end 0.67945 0.3048)
			(stroke
				(width 0.1)
				(type default)
			)
			(layer "F.Fab")
		)
		(fp_line
			(start -0.67945 -0.305054)
			(end -0.12065 -0.305054)
			(stroke
				(width 0.1)
				(type default)
			)
			(layer "F.Fab")
		)
		(fp_line
			(start -0.12065 -0.305054)
			(end -0.12065 -0.2794)
			(stroke
				(width 0.1)
				(type default)
			)
			(layer "F.Fab")
		)
		(pad "1" smd circle
			(at -0.40005 0 270)
			(size 0 0)
			(layers "F.Cu" "F.Mask" "F.Paste")
			(net "GND")
		)
		(pad "2" smd circle
			(at 0.40005 0 270)
			(size 0 0)
			(layers "F.Cu" "F.Mask" "F.Paste")
			(net "PVCCIN_CPU1_VREF")
		)
	)
	(footprint ""
		(layer "F.Cu")
		(at 94.045278 -93.063314)
		(property "Reference" "Q98"
			(at 0.57658 1.975612 0)
			(unlocked yes)
			(layer "F.SilkS")
			(effects
				(font
					(size 0.7874 0.5842)
					(thickness 0.1524)
				)
			)
		)
		(property "Value" ""
			(at 0 0 0)
			(layer "F.Fab")
			(effects
				(font
					(size 1.27 1.27)
				)
			)
		)
		(duplicate_pad_numbers_are_jumpers no)
		(fp_line
			(start -1.376172 -1.199896)
			(end -0.508 -1.199896)
			(stroke
				(width 0.1524)
				(type default)
			)
			(layer "F.SilkS")
		)
		(fp_line
			(start -1.376172 1.199896)
			(end -1.376172 -1.199896)
			(stroke
				(width 0.1524)
				(type default)
			)
			(layer "F.SilkS")
		)
		(fp_line
			(start -0.508 -1.199896)
			(end 0 -0.762)
			(stroke
				(width 0.1524)
				(type default)
			)
			(layer "F.SilkS")
		)
		(fp_line
			(start 0 -0.762)
			(end 0.508 -1.199896)
			(stroke
				(width 0.1524)
				(type default)
			)
			(layer "F.SilkS")
		)
		(fp_line
			(start 0.508 -1.199896)
			(end 1.376172 -1.199896)
			(stroke
				(width 0.1524)
				(type default)
			)
			(layer "F.SilkS")
		)
		(fp_line
			(start 1.376172 -1.199896)
			(end 1.376172 1.199896)
			(stroke
				(width 0.1524)
				(type default)
			)
			(layer "F.SilkS")
		)
		(fp_line
			(start 1.376172 1.199896)
			(end -1.376172 1.199896)
			(stroke
				(width 0.1524)
				(type default)
			)
			(layer "F.SilkS")
		)
		(fp_poly
			(pts
				(xy -1.4605 -0.7493) (xy -2.2225 -0.3683) (xy -2.2225 -1.1303)
			)
			(stroke
				(width 0)
				(type default)
			)
			(fill yes)
			(layer "F.SilkS")
		)
		(fp_line
			(start -0.674878 -1.100074)
			(end 0.674878 -1.100074)
			(stroke
				(width 0.1)
				(type default)
			)
			(layer "F.Fab")
		)
		(fp_line
			(start -0.674878 1.100074)
			(end -0.674878 -1.100074)
			(stroke
				(width 0.1)
				(type default)
			)
			(layer "F.Fab")
		)
		(fp_line
			(start 0.674878 -1.100074)
			(end 0.674878 1.100074)
			(stroke
				(width 0.1)
				(type default)
			)
			(layer "F.Fab")
		)
		(fp_line
			(start 0.674878 1.100074)
			(end -0.674878 1.100074)
			(stroke
				(width 0.1)
				(type default)
			)
			(layer "F.Fab")
		)
		(fp_poly
			(pts
				(xy -1.4605 -0.7493) (xy -2.2225 -1.1303) (xy -2.2225 -0.3683)
			)
			(stroke
				(width 0)
				(type default)
			)
			(fill yes)
			(layer "F.Fab")
		)
		(pad "1" smd rect
			(at -0.899922 -0.750062 270)
			(size 0.6096 0.6096)
			(layers "F.Cu" "F.Mask" "F.Paste")
			(net "GND")
		)
		(pad "2" smd rect
			(at -0.899922 0 270)
			(size 0.4064 0.6096)
			(layers "F.Cu" "F.Mask" "F.Paste")
			(net "RST_PLD_CPU0_DRAM_AB_N")
		)
		(pad "3" smd rect
			(at -0.899922 0.750062 270)
			(size 0.6096 0.6096)
			(layers "F.Cu" "F.Mask" "F.Paste")
			(net "LED_RST_PLD_CPU0_DRAM_CD_N_D")
		)
		(pad "4" smd rect
			(at 0.899922 0.750062 270)
			(size 0.6096 0.6096)
			(layers "F.Cu" "F.Mask" "F.Paste")
			(net "GND")
		)
		(pad "5" smd rect
			(at 0.899922 0 270)
			(size 0.4064 0.6096)
			(layers "F.Cu" "F.Mask" "F.Paste")
			(net "RST_PLD_CPU0_DRAM_CD_N")
		)
		(pad "6" smd rect
			(at 0.899922 -0.750062 270)
			(size 0.6096 0.6096)
			(layers "F.Cu" "F.Mask" "F.Paste")
			(net "LED_RST_PLD_CPU0_DRAM_AB_N_D")
		)
	)
)
